(kicad_pcb
	(version 20260206)
	(generator "pcbnew")
	(generator_version "10.0")
	(general
		(thickness 1.6)
		(legacy_teardrops no)
	)
	(paper "A4")
	(title_block
		(title "03242023_DA0F0TMBIJ0_F0T_Motherboard_J_brd_V01_OCP.brd")
		(comment 1 "Grand Teton / footprints 3611-3616 of 6105")
	)
	(layers
		(0 "F.Cu" signal "TOP")
		(4 "In1.Cu" signal "GND")
		(6 "In2.Cu" signal "IN1")
		(8 "In3.Cu" signal "GND1")
		(10 "In4.Cu" signal "IN2")
		(12 "In5.Cu" signal "GND2")
		(14 "In6.Cu" signal "IN3")
		(16 "In7.Cu" signal "GND3")
		(18 "In8.Cu" signal "VCC")
		(20 "In9.Cu" signal "VCC1")
		(22 "In10.Cu" signal "GND4")
		(24 "In11.Cu" signal "IN4")
		(26 "In12.Cu" signal "GND5")
		(28 "In13.Cu" signal "IN5")
		(30 "In14.Cu" signal "GND6")
		(32 "In15.Cu" signal "IN6")
		(34 "In16.Cu" signal "GND7")
		(2 "B.Cu" signal "BOTTOM")
		(9 "F.Adhes" user "F.Adhesive")
		(11 "B.Adhes" user "B.Adhesive")
		(13 "F.Paste" user "Package Geometry/Pastemask Top")
		(15 "B.Paste" user "Package Geometry/Pastemask Bottom")
		(5 "F.SilkS" user "Ref Des/Silkscreen Top")
		(7 "B.SilkS" user "Ref Des/Silkscreen Bottom")
		(1 "F.Mask" user "Board Geometry/Soldermask Top")
		(3 "B.Mask" user "Board Geometry/Soldermask Bottom")
		(17 "Dwgs.User" user "User.Drawings")
		(19 "Cmts.User" user "User.Comments")
		(21 "Eco1.User" user "User.Eco1")
		(23 "Eco2.User" user "User.Eco2")
		(25 "Edge.Cuts" user "Board Geometry/Outline")
		(27 "Margin" user)
		(31 "F.CrtYd" user "Package Geometry/Place Bound Top")
		(29 "B.CrtYd" user "Package Geometry/Place Bound Bottom")
		(35 "F.Fab" user "Ref Des/Assembly Top")
		(33 "B.Fab" user "Ref Des/Assembly Bottom")
	)
	(footprint ""
		(layer "F.Cu")
		(at 51.593496 -116.52377)
		(property "Reference" "R3705"
			(at 0 0 0)
			(layer "F.SilkS")
			(hide yes)
			(effects
				(font
					(size 1.27 1.27)
				)
			)
		)
		(property "Value" ""
			(at 0 0 0)
			(layer "F.Fab")
			(effects
				(font
					(size 1.27 1.27)
				)
			)
		)
		(duplicate_pad_numbers_are_jumpers no)
		(fp_line
			(start -0.7874 -0.4064)
			(end 0.7874 -0.4064)
			(stroke
				(width 0.1524)
				(type default)
			)
			(layer "F.SilkS")
		)
		(fp_line
			(start -0.7874 0.4064)
			(end -0.7874 -0.4064)
			(stroke
				(width 0.1524)
				(type default)
			)
			(layer "F.SilkS")
		)
		(fp_line
			(start 0.7874 -0.4064)
			(end 0.7874 0.4064)
			(stroke
				(width 0.1524)
				(type default)
			)
			(layer "F.SilkS")
		)
		(fp_line
			(start 0.7874 0.4064)
			(end -0.7874 0.4064)
			(stroke
				(width 0.1524)
				(type default)
			)
			(layer "F.SilkS")
		)
		(fp_line
			(start -0.67945 -0.305054)
			(end -0.12065 -0.305054)
			(stroke
				(width 0.1)
				(type default)
			)
			(layer "F.Fab")
		)
		(fp_line
			(start -0.67945 0.3048)
			(end -0.67945 -0.305054)
			(stroke
				(width 0.1)
				(type default)
			)
			(layer "F.Fab")
		)
		(fp_line
			(start -0.12065 -0.305054)
			(end -0.12065 -0.2794)
			(stroke
				(width 0.1)
				(type default)
			)
			(layer "F.Fab")
		)
		(fp_line
			(start -0.12065 -0.2794)
			(end 0.12065 -0.2794)
			(stroke
				(width 0.1)
				(type default)
			)
			(layer "F.Fab")
		)
		(fp_line
			(start -0.12065 0.2794)
			(end -0.12065 0.3048)
			(stroke
				(width 0.1)
				(type default)
			)
			(layer "F.Fab")
		)
		(fp_line
			(start -0.12065 0.3048)
			(end -0.67945 0.3048)
			(stroke
				(width 0.1)
				(type default)
			)
			(layer "F.Fab")
		)
		(fp_line
			(start 0.120396 0.2794)
			(end -0.12065 0.2794)
			(stroke
				(width 0.1)
				(type default)
			)
			(layer "F.Fab")
		)
		(fp_line
			(start 0.120396 0.3048)
			(end 0.120396 0.2794)
			(stroke
				(width 0.1)
				(type default)
			)
			(layer "F.Fab")
		)
		(fp_line
			(start 0.12065 -0.3048)
			(end 0.67945 -0.3048)
			(stroke
				(width 0.1)
				(type default)
			)
			(layer "F.Fab")
		)
		(fp_line
			(start 0.12065 -0.2794)
			(end 0.12065 -0.3048)
			(stroke
				(width 0.1)
				(type default)
			)
			(layer "F.Fab")
		)
		(fp_line
			(start 0.67945 -0.3048)
			(end 0.67945 0.3048)
			(stroke
				(width 0.1)
				(type default)
			)
			(layer "F.Fab")
		)
		(fp_line
			(start 0.67945 0.3048)
			(end 0.120396 0.3048)
			(stroke
				(width 0.1)
				(type default)
			)
			(layer "F.Fab")
		)
		(pad "1" smd circle
			(at -0.40005 0)
			(size 0 0)
			(layers "F.Cu" "F.Mask" "F.Paste")
			(net "P3V3_AUX")
		)
		(pad "2" smd circle
			(at 0.40005 0)
			(size 0 0)
			(layers "F.Cu" "F.Mask" "F.Paste")
			(net "RST_SMB_SWITCH_N")
		)
	)
	(footprint ""
		(layer "F.Cu")
		(at 303.08804 -362.843826 -90)
		(property "Reference" "PC605_P0_2"
			(at 0 0 270)
			(layer "F.SilkS")
			(hide yes)
			(effects
				(font
					(size 1.27 1.27)
				)
			)
		)
		(property "Value" ""
			(at 0 0 270)
			(layer "F.Fab")
			(effects
				(font
					(size 1.27 1.27)
				)
			)
		)
		(duplicate_pad_numbers_are_jumpers no)
		(fp_line
			(start -0.7874 0.4064)
			(end -0.7874 -0.4064)
			(stroke
				(width 0.1524)
				(type default)
			)
			(layer "F.SilkS")
		)
		(fp_line
			(start 0.7874 0.4064)
			(end -0.7874 0.4064)
			(stroke
				(width 0.1524)
				(type default)
			)
			(layer "F.SilkS")
		)
		(fp_line
			(start -0.7874 -0.4064)
			(end 0.7874 -0.4064)
			(stroke
				(width 0.1524)
				(type default)
			)
			(layer "F.SilkS")
		)
		(fp_line
			(start 0.7874 -0.4064)
			(end 0.7874 0.4064)
			(stroke
				(width 0.1524)
				(type default)
			)
			(layer "F.SilkS")
		)
		(fp_line
			(start -0.67945 0.3048)
			(end -0.67945 -0.305054)
			(stroke
				(width 0.1)
				(type default)
			)
			(layer "F.Fab")
		)
		(fp_line
			(start -0.12065 0.3048)
			(end -0.67945 0.3048)
			(stroke
				(width 0.1)
				(type default)
			)
			(layer "F.Fab")
		)
		(fp_line
			(start 0.120396 0.3048)
			(end 0.120396 0.2794)
			(stroke
				(width 0.1)
				(type default)
			)
			(layer "F.Fab")
		)
		(fp_line
			(start 0.67945 0.3048)
			(end 0.120396 0.3048)
			(stroke
				(width 0.1)
				(type default)
			)
			(layer "F.Fab")
		)
		(fp_line
			(start -0.12065 0.2794)
			(end -0.12065 0.3048)
			(stroke
				(width 0.1)
				(type default)
			)
			(layer "F.Fab")
		)
		(fp_line
			(start 0.120396 0.2794)
			(end -0.12065 0.2794)
			(stroke
				(width 0.1)
				(type default)
			)
			(layer "F.Fab")
		)
		(fp_line
			(start -0.12065 -0.2794)
			(end 0.12065 -0.2794)
			(stroke
				(width 0.1)
				(type default)
			)
			(layer "F.Fab")
		)
		(fp_line
			(start 0.12065 -0.2794)
			(end 0.12065 -0.3048)
			(stroke
				(width 0.1)
				(type default)
			)
			(layer "F.Fab")
		)
		(fp_line
			(start 0.12065 -0.3048)
			(end 0.67945 -0.3048)
			(stroke
				(width 0.1)
				(type default)
			)
			(layer "F.Fab")
		)
		(fp_line
			(start 0.67945 -0.3048)
			(end 0.67945 0.3048)
			(stroke
				(width 0.1)
				(type default)
			)
			(layer "F.Fab")
		)
		(fp_line
			(start -0.67945 -0.305054)
			(end -0.12065 -0.305054)
			(stroke
				(width 0.1)
				(type default)
			)
			(layer "F.Fab")
		)
		(fp_line
			(start -0.12065 -0.305054)
			(end -0.12065 -0.2794)
			(stroke
				(width 0.1)
				(type default)
			)
			(layer "F.Fab")
		)
		(pad "1" smd circle
			(at -0.40005 0 270)
			(size 0 0)
			(layers "F.Cu" "F.Mask" "F.Paste")
			(net "SW_P12V_PVCCFA_EHV_FIVRA_CPU0_L")
		)
		(pad "2" smd circle
			(at 0.40005 0 270)
			(size 0 0)
			(layers "F.Cu" "F.Mask" "F.Paste")
			(net "GND")
		)
	)
	(footprint ""
		(layer "F.Cu")
		(at 52.480972 -435.360318 180)
		(property "Reference" "R3524"
			(at 0 0 180)
			(layer "F.SilkS")
			(hide yes)
			(effects
				(font
					(size 1.27 1.27)
				)
			)
		)
		(property "Value" ""
			(at 0 0 180)
			(layer "F.Fab")
			(effects
				(font
					(size 1.27 1.27)
				)
			)
		)
		(duplicate_pad_numbers_are_jumpers no)
		(fp_line
			(start 0.7874 0.4064)
			(end -0.7874 0.4064)
			(stroke
				(width 0.1524)
				(type default)
			)
			(layer "F.SilkS")
		)
		(fp_line
			(start 0.7874 -0.4064)
			(end 0.7874 0.4064)
			(stroke
				(width 0.1524)
				(type default)
			)
			(layer "F.SilkS")
		)
		(fp_line
			(start -0.7874 0.4064)
			(end -0.7874 -0.4064)
			(stroke
				(width 0.1524)
				(type default)
			)
			(layer "F.SilkS")
		)
		(fp_line
			(start -0.7874 -0.4064)
			(end 0.7874 -0.4064)
			(stroke
				(width 0.1524)
				(type default)
			)
			(layer "F.SilkS")
		)
		(fp_line
			(start 0.67945 0.3048)
			(end 0.120396 0.3048)
			(stroke
				(width 0.1)
				(type default)
			)
			(layer "F.Fab")
		)
		(fp_line
			(start 0.67945 -0.3048)
			(end 0.67945 0.3048)
			(stroke
				(width 0.1)
				(type default)
			)
			(layer "F.Fab")
		)
		(fp_line
			(start 0.12065 -0.2794)
			(end 0.12065 -0.3048)
			(stroke
				(width 0.1)
				(type default)
			)
			(layer "F.Fab")
		)
		(fp_line
			(start 0.12065 -0.3048)
			(end 0.67945 -0.3048)
			(stroke
				(width 0.1)
				(type default)
			)
			(layer "F.Fab")
		)
		(fp_line
			(start 0.120396 0.3048)
			(end 0.120396 0.2794)
			(stroke
				(width 0.1)
				(type default)
			)
			(layer "F.Fab")
		)
		(fp_line
			(start 0.120396 0.2794)
			(end -0.12065 0.2794)
			(stroke
				(width 0.1)
				(type default)
			)
			(layer "F.Fab")
		)
		(fp_line
			(start -0.12065 0.3048)
			(end -0.67945 0.3048)
			(stroke
				(width 0.1)
				(type default)
			)
			(layer "F.Fab")
		)
		(fp_line
			(start -0.12065 0.2794)
			(end -0.12065 0.3048)
			(stroke
				(width 0.1)
				(type default)
			)
			(layer "F.Fab")
		)
		(fp_line
			(start -0.12065 -0.2794)
			(end 0.12065 -0.2794)
			(stroke
				(width 0.1)
				(type default)
			)
			(layer "F.Fab")
		)
		(fp_line
			(start -0.12065 -0.305054)
			(end -0.12065 -0.2794)
			(stroke
				(width 0.1)
				(type default)
			)
			(layer "F.Fab")
		)
		(fp_line
			(start -0.67945 0.3048)
			(end -0.67945 -0.305054)
			(stroke
				(width 0.1)
				(type default)
			)
			(layer "F.Fab")
		)
		(fp_line
			(start -0.67945 -0.305054)
			(end -0.12065 -0.305054)
			(stroke
				(width 0.1)
				(type default)
			)
			(layer "F.Fab")
		)
		(pad "1" smd circle
			(at -0.40005 0 180)
			(size 0 0)
			(layers "F.Cu" "F.Mask" "F.Paste")
			(net "P3V3_AUX")
		)
		(pad "2" smd circle
			(at 0.40005 0 180)
			(size 0 0)
			(layers "F.Cu" "F.Mask" "F.Paste")
			(net "SMB_1_BMC_GPU_BUF_R_SDA")
		)
	)
	(footprint ""
		(layer "F.Cu")
		(at 406.124664 -360.722926)
		(property "Reference" "R332"
			(at 0 0 0)
			(layer "F.SilkS")
			(hide yes)
			(effects
				(font
					(size 1.27 1.27)
				)
			)
		)
		(property "Value" ""
			(at 0 0 0)
			(layer "F.Fab")
			(effects
				(font
					(size 1.27 1.27)
				)
			)
		)
		(duplicate_pad_numbers_are_jumpers no)
		(fp_line
			(start -0.7874 -0.4064)
			(end 0.7874 -0.4064)
			(stroke
				(width 0.1524)
				(type default)
			)
			(layer "F.SilkS")
		)
		(fp_line
			(start -0.7874 0.4064)
			(end -0.7874 -0.4064)
			(stroke
				(width 0.1524)
				(type default)
			)
			(layer "F.SilkS")
		)
		(fp_line
			(start 0.7874 -0.4064)
			(end 0.7874 0.4064)
			(stroke
				(width 0.1524)
				(type default)
			)
			(layer "F.SilkS")
		)
		(fp_line
			(start 0.7874 0.4064)
			(end -0.7874 0.4064)
			(stroke
				(width 0.1524)
				(type default)
			)
			(layer "F.SilkS")
		)
		(fp_line
			(start -0.67945 -0.305054)
			(end -0.12065 -0.305054)
			(stroke
				(width 0.1)
				(type default)
			)
			(layer "F.Fab")
		)
		(fp_line
			(start -0.67945 0.3048)
			(end -0.67945 -0.305054)
			(stroke
				(width 0.1)
				(type default)
			)
			(layer "F.Fab")
		)
		(fp_line
			(start -0.12065 -0.305054)
			(end -0.12065 -0.2794)
			(stroke
				(width 0.1)
				(type default)
			)
			(layer "F.Fab")
		)
		(fp_line
			(start -0.12065 -0.2794)
			(end 0.12065 -0.2794)
			(stroke
				(width 0.1)
				(type default)
			)
			(layer "F.Fab")
		)
		(fp_line
			(start -0.12065 0.2794)
			(end -0.12065 0.3048)
			(stroke
				(width 0.1)
				(type default)
			)
			(layer "F.Fab")
		)
		(fp_line
			(start -0.12065 0.3048)
			(end -0.67945 0.3048)
			(stroke
				(width 0.1)
				(type default)
			)
			(layer "F.Fab")
		)
		(fp_line
			(start 0.120396 0.2794)
			(end -0.12065 0.2794)
			(stroke
				(width 0.1)
				(type default)
			)
			(layer "F.Fab")
		)
		(fp_line
			(start 0.120396 0.3048)
			(end 0.120396 0.2794)
			(stroke
				(width 0.1)
				(type default)
			)
			(layer "F.Fab")
		)
		(fp_line
			(start 0.12065 -0.3048)
			(end 0.67945 -0.3048)
			(stroke
				(width 0.1)
				(type default)
			)
			(layer "F.Fab")
		)
		(fp_line
			(start 0.12065 -0.2794)
			(end 0.12065 -0.3048)
			(stroke
				(width 0.1)
				(type default)
			)
			(layer "F.Fab")
		)
		(fp_line
			(start 0.67945 -0.3048)
			(end 0.67945 0.3048)
			(stroke
				(width 0.1)
				(type default)
			)
			(layer "F.Fab")
		)
		(fp_line
			(start 0.67945 0.3048)
			(end 0.120396 0.3048)
			(stroke
				(width 0.1)
				(type default)
			)
			(layer "F.Fab")
		)
		(pad "1" smd circle
			(at -0.40005 0)
			(size 0 0)
			(layers "F.Cu" "F.Mask" "F.Paste")
			(net "PD_PIROM_CPU0_ADDR2")
		)
		(pad "2" smd circle
			(at 0.40005 0)
			(size 0 0)
			(layers "F.Cu" "F.Mask" "F.Paste")
			(net "GND")
		)
	)
	(footprint ""
		(layer "F.Cu")
		(at 274.271486 -394.17117)
		(property "Reference" "PR2531"
			(at 0 0 0)
			(layer "F.SilkS")
			(hide yes)
			(effects
				(font
					(size 1.27 1.27)
				)
			)
		)
		(property "Value" ""
			(at 0 0 0)
			(layer "F.Fab")
			(effects
				(font
					(size 1.27 1.27)
				)
			)
		)
		(duplicate_pad_numbers_are_jumpers no)
		(fp_line
			(start -0.7874 -0.4064)
			(end 0.7874 -0.4064)
			(stroke
				(width 0.1524)
				(type default)
			)
			(layer "F.SilkS")
		)
		(fp_line
			(start -0.7874 0.4064)
			(end -0.7874 -0.4064)
			(stroke
				(width 0.1524)
				(type default)
			)
			(layer "F.SilkS")
		)
		(fp_line
			(start 0.7874 -0.4064)
			(end 0.7874 0.4064)
			(stroke
				(width 0.1524)
				(type default)
			)
			(layer "F.SilkS")
		)
		(fp_line
			(start 0.7874 0.4064)
			(end -0.7874 0.4064)
			(stroke
				(width 0.1524)
				(type default)
			)
			(layer "F.SilkS")
		)
		(fp_line
			(start -0.67945 -0.305054)
			(end -0.12065 -0.305054)
			(stroke
				(width 0.1)
				(type default)
			)
			(layer "F.Fab")
		)
		(fp_line
			(start -0.67945 0.3048)
			(end -0.67945 -0.305054)
			(stroke
				(width 0.1)
				(type default)
			)
			(layer "F.Fab")
		)
		(fp_line
			(start -0.12065 -0.305054)
			(end -0.12065 -0.2794)
			(stroke
				(width 0.1)
				(type default)
			)
			(layer "F.Fab")
		)
		(fp_line
			(start -0.12065 -0.2794)
			(end 0.12065 -0.2794)
			(stroke
				(width 0.1)
				(type default)
			)
			(layer "F.Fab")
		)
		(fp_line
			(start -0.12065 0.2794)
			(end -0.12065 0.3048)
			(stroke
				(width 0.1)
				(type default)
			)
			(layer "F.Fab")
		)
		(fp_line
			(start -0.12065 0.3048)
			(end -0.67945 0.3048)
			(stroke
				(width 0.1)
				(type default)
			)
			(layer "F.Fab")
		)
		(fp_line
			(start 0.120396 0.2794)
			(end -0.12065 0.2794)
			(stroke
				(width 0.1)
				(type default)
			)
			(layer "F.Fab")
		)
		(fp_line
			(start 0.120396 0.3048)
			(end 0.120396 0.2794)
			(stroke
				(width 0.1)
				(type default)
			)
			(layer "F.Fab")
		)
		(fp_line
			(start 0.12065 -0.3048)
			(end 0.67945 -0.3048)
			(stroke
				(width 0.1)
				(type default)
			)
			(layer "F.Fab")
		)
		(fp_line
			(start 0.12065 -0.2794)
			(end 0.12065 -0.3048)
			(stroke
				(width 0.1)
				(type default)
			)
			(layer "F.Fab")
		)
		(fp_line
			(start 0.67945 -0.3048)
			(end 0.67945 0.3048)
			(stroke
				(width 0.1)
				(type default)
			)
			(layer "F.Fab")
		)
		(fp_line
			(start 0.67945 0.3048)
			(end 0.120396 0.3048)
			(stroke
				(width 0.1)
				(type default)
			)
			(layer "F.Fab")
		)
		(pad "1" smd circle
			(at -0.40005 0)
			(size 0 0)
			(layers "F.Cu" "F.Mask" "F.Paste")
			(net "P12V_HSC_GATE_G4")
		)
		(pad "2" smd circle
			(at 0.40005 0)
			(size 0 0)
			(layers "F.Cu" "F.Mask" "F.Paste")
			(net "P12V_HSC_GATE2")
		)
	)
	(footprint ""
		(layer "F.Cu")
		(at 417.43757 -45.83684 180)
		(property "Reference" "C1172"
			(at 0 0 180)
			(layer "F.SilkS")
			(hide yes)
			(effects
				(font
					(size 1.27 1.27)
				)
			)
		)
		(property "Value" ""
			(at 0 0 180)
			(layer "F.Fab")
			(effects
				(font
					(size 1.27 1.27)
				)
			)
		)
		(duplicate_pad_numbers_are_jumpers no)
		(fp_line
			(start 0.7874 0.4064)
			(end -0.7874 0.4064)
			(stroke
				(width 0.1524)
				(type default)
			)
			(layer "F.SilkS")
		)
		(fp_line
			(start 0.7874 -0.4064)
			(end 0.7874 0.4064)
			(stroke
				(width 0.1524)
				(type default)
			)
			(layer "F.SilkS")
		)
		(fp_line
			(start -0.7874 0.4064)
			(end -0.7874 -0.4064)
			(stroke
				(width 0.1524)
				(type default)
			)
			(layer "F.SilkS")
		)
		(fp_line
			(start -0.7874 -0.4064)
			(end 0.7874 -0.4064)
			(stroke
				(width 0.1524)
				(type default)
			)
			(layer "F.SilkS")
		)
		(fp_line
			(start 0.67945 0.3048)
			(end 0.120396 0.3048)
			(stroke
				(width 0.1)
				(type default)
			)
			(layer "F.Fab")
		)
		(fp_line
			(start 0.67945 -0.3048)
			(end 0.67945 0.3048)
			(stroke
				(width 0.1)
				(type default)
			)
			(layer "F.Fab")
		)
		(fp_line
			(start 0.12065 -0.2794)
			(end 0.12065 -0.3048)
			(stroke
				(width 0.1)
				(type default)
			)
			(layer "F.Fab")
		)
		(fp_line
			(start 0.12065 -0.3048)
			(end 0.67945 -0.3048)
			(stroke
				(width 0.1)
				(type default)
			)
			(layer "F.Fab")
		)
		(fp_line
			(start 0.120396 0.3048)
			(end 0.120396 0.2794)
			(stroke
				(width 0.1)
				(type default)
			)
			(layer "F.Fab")
		)
		(fp_line
			(start 0.120396 0.2794)
			(end -0.12065 0.2794)
			(stroke
				(width 0.1)
				(type default)
			)
			(layer "F.Fab")
		)
		(fp_line
			(start -0.12065 0.3048)
			(end -0.67945 0.3048)
			(stroke
				(width 0.1)
				(type default)
			)
			(layer "F.Fab")
		)
		(fp_line
			(start -0.12065 0.2794)
			(end -0.12065 0.3048)
			(stroke
				(width 0.1)
				(type default)
			)
			(layer "F.Fab")
		)
		(fp_line
			(start -0.12065 -0.2794)
			(end 0.12065 -0.2794)
			(stroke
				(width 0.1)
				(type default)
			)
			(layer "F.Fab")
		)
		(fp_line
			(start -0.12065 -0.305054)
			(end -0.12065 -0.2794)
			(stroke
				(width 0.1)
				(type default)
			)
			(layer "F.Fab")
		)
		(fp_line
			(start -0.67945 0.3048)
			(end -0.67945 -0.305054)
			(stroke
				(width 0.1)
				(type default)
			)
			(layer "F.Fab")
		)
		(fp_line
			(start -0.67945 -0.305054)
			(end -0.12065 -0.305054)
			(stroke
				(width 0.1)
				(type default)
			)
			(layer "F.Fab")
		)
		(pad "1" smd circle
			(at -0.40005 0 180)
			(size 0 0)
			(layers "F.Cu" "F.Mask" "F.Paste")
			(net "P5V")
		)
		(pad "2" smd circle
			(at 0.40005 0 180)
			(size 0 0)
			(layers "F.Cu" "F.Mask" "F.Paste")
			(net "GND")
		)
	)
)
